# BASEBOARD_FAB2 (Tioga Pass) — schematic netlist excerpt (pin names and nets, part order shuffled) for the footprints in the layout excerpt that follows; sources: Cadence DE-HDL packaged netlist, KiCad conversion of Wiwynn_Tioga_Pass_MB.brd

C5G10  CAP_A  47UF 4V 20% X5R  pkg 0603V  page 217 : A = PVDDQ_ABC ; B = GND
C1E18  CAPP  270UF 16V 20% OSCON  pkg 2626  page 209 : A = VR_FET_SW_P12V_STBY_PVCCIN_CPU1 ; B = GND

(kicad_pcb
	(version 20260206)
	(generator "pcbnew")
	(generator_version "10.0")
	(general
		(thickness 1.6)
		(legacy_teardrops no)
	)
	(paper "A4")
	(title_block
		(title "Wiwynn_Tioga_Pass_MB.brd")
		(comment 1 "Tioga Pass / footprints 136-137 of 4770")
	)
	(layers
		(0 "F.Cu" signal "TOP")
		(4 "In1.Cu" signal "L2GND")
		(6 "In2.Cu" signal "L3")
		(8 "In3.Cu" signal "L4GND")
		(10 "In4.Cu" signal "L5")
		(12 "In5.Cu" signal "L6GND")
		(14 "In6.Cu" signal "L7VCC")
		(16 "In7.Cu" signal "L8VCC")
		(18 "In8.Cu" signal "L9GND")
		(20 "In9.Cu" signal "L10")
		(22 "In10.Cu" signal "L11GND")
		(24 "In11.Cu" signal "L12")
		(26 "In12.Cu" signal "L13GND")
		(2 "B.Cu" signal "BOTTOM")
		(9 "F.Adhes" user "F.Adhesive")
		(11 "B.Adhes" user "B.Adhesive")
		(13 "F.Paste" user "Package Geometry/Pastemask Top")
		(15 "B.Paste" user "Package Geometry/Pastemask Bottom")
		(5 "F.SilkS" user "Ref Des/Silkscreen Top")
		(7 "B.SilkS" user "Ref Des/Silkscreen Bottom")
		(1 "F.Mask" user "Board Geometry/Soldermask Top")
		(3 "B.Mask" user "Board Geometry/Soldermask Bottom")
		(17 "Dwgs.User" user "User.Drawings")
		(19 "Cmts.User" user "User.Comments")
		(21 "Eco1.User" user "User.Eco1")
		(23 "Eco2.User" user "User.Eco2")
		(25 "Edge.Cuts" user "Board Geometry/Outline")
		(27 "Margin" user)
		(31 "F.CrtYd" user "Package Geometry/Place Bound Top")
		(29 "B.CrtYd" user "Package Geometry/Place Bound Bottom")
		(35 "F.Fab" user "Ref Des/Assembly Top")
		(33 "B.Fab" user "Ref Des/Assembly Bottom")
	)
	(footprint ""
		(layer "F.Cu")
		(at 25.7048 -50.419)
		(property "Reference" "C1E18"
			(at 4.16687 3.302 90)
			(unlocked yes)
			(layer "F.SilkS")
			(effects
				(font
					(size 0.7874 0.5842)
					(thickness 0.1524)
				)
				(justify left)
			)
		)
		(property "Value" ""
			(at 0 0 0)
			(layer "F.Fab")
			(effects
				(font
					(size 1.27 1.27)
				)
			)
		)
		(duplicate_pad_numbers_are_jumpers no)
		(fp_line
			(start -3.400044 0.028956)
			(end -3.400044 6.067044)
			(stroke
				(width 0.1524)
				(type default)
			)
			(layer "F.SilkS")
		)
		(fp_line
			(start -3.400044 6.067044)
			(end -0.9017 6.067044)
			(stroke
				(width 0.1524)
				(type default)
			)
			(layer "F.SilkS")
		)
		(fp_line
			(start -2.638044 -0.733044)
			(end -3.400044 0.028956)
			(stroke
				(width 0.1524)
				(type default)
			)
			(layer "F.SilkS")
		)
		(fp_line
			(start -0.9017 -1.714246)
			(end -0.9017 1.587754)
			(stroke
				(width 0.1524)
				(type default)
			)
			(layer "F.SilkS")
		)
		(fp_line
			(start -0.9017 -0.733044)
			(end -2.638044 -0.733044)
			(stroke
				(width 0.1524)
				(type default)
			)
			(layer "F.SilkS")
		)
		(fp_line
			(start -0.9017 1.587754)
			(end -0.7239 1.587754)
			(stroke
				(width 0.1524)
				(type default)
			)
			(layer "F.SilkS")
		)
		(fp_line
			(start -0.7239 -1.714246)
			(end -0.9017 -1.714246)
			(stroke
				(width 0.1524)
				(type default)
			)
			(layer "F.SilkS")
		)
		(fp_line
			(start 0.7239 1.587754)
			(end 0.9017 1.587754)
			(stroke
				(width 0.1524)
				(type default)
			)
			(layer "F.SilkS")
		)
		(fp_line
			(start 0.9017 -1.714246)
			(end 0.7239 -1.714246)
			(stroke
				(width 0.1524)
				(type default)
			)
			(layer "F.SilkS")
		)
		(fp_line
			(start 0.9017 1.587754)
			(end 0.9017 -1.714246)
			(stroke
				(width 0.1524)
				(type default)
			)
			(layer "F.SilkS")
		)
		(fp_line
			(start 0.9017 6.067044)
			(end 3.400044 6.067044)
			(stroke
				(width 0.1524)
				(type default)
			)
			(layer "F.SilkS")
		)
		(fp_line
			(start 2.638044 -0.733044)
			(end 0.9017 -0.733044)
			(stroke
				(width 0.1524)
				(type default)
			)
			(layer "F.SilkS")
		)
		(fp_line
			(start 3.400044 0.028956)
			(end 2.638044 -0.733044)
			(stroke
				(width 0.1524)
				(type default)
			)
			(layer "F.SilkS")
		)
		(fp_line
			(start 3.400044 6.067044)
			(end 3.400044 0.028956)
			(stroke
				(width 0.1524)
				(type default)
			)
			(layer "F.SilkS")
		)
		(fp_poly
			(pts
				(xy -3.400044 6.067044) (xy 3.400044 6.067044) (xy 3.400044 0.028956) (xy 2.638044 -0.733044) (xy -2.638044 -0.733044)
				(xy -3.400044 0.028956)
			)
			(stroke
				(width 0)
				(type default)
			)
			(fill no)
			(layer "F.CrtYd")
		)
		(fp_line
			(start -3.400044 0.028956)
			(end -3.400044 6.067044)
			(stroke
				(width 0.1)
				(type default)
			)
			(layer "F.Fab")
		)
		(fp_line
			(start -3.400044 6.067044)
			(end 3.400044 6.067044)
			(stroke
				(width 0.1)
				(type default)
			)
			(layer "F.Fab")
		)
		(fp_line
			(start -2.638044 -0.733044)
			(end -3.400044 0.028956)
			(stroke
				(width 0.1)
				(type default)
			)
			(layer "F.Fab")
		)
		(fp_line
			(start 2.638044 -0.733044)
			(end -2.638044 -0.733044)
			(stroke
				(width 0.1)
				(type default)
			)
			(layer "F.Fab")
		)
		(fp_line
			(start 3.400044 0.028956)
			(end 2.638044 -0.733044)
			(stroke
				(width 0.1)
				(type default)
			)
			(layer "F.Fab")
		)
		(fp_line
			(start 3.400044 6.067044)
			(end 3.400044 0.028956)
			(stroke
				(width 0.1)
				(type default)
			)
			(layer "F.Fab")
		)
		(fp_circle
			(center 0 2.667)
			(end 3.400044 2.667)
			(stroke
				(width 0.1)
				(type default)
			)
			(fill no)
			(layer "F.Fab")
		)
		(pad "1" smd rect
			(at 0 0)
			(size 0.7874 3.429)
			(layers "F.Cu" "F.Mask" "F.Paste")
			(net "VR_FET_SW_P12V_STBY_PVCCIN_CPU1")
		)
		(pad "2" smd rect
			(at 0 5.334)
			(size 0.7874 3.429)
			(layers "F.Cu" "F.Mask" "F.Paste")
			(net "GND")
		)
	)
	(footprint ""
		(layer "F.Cu")
		(at 258.1656 -12.9032 -90)
		(property "Reference" "C5G10"
			(at 0 0 270)
			(layer "F.SilkS")
			(hide yes)
			(effects
				(font
					(size 1.27 1.27)
				)
			)
		)
		(property "Value" ""
			(at 0 0 270)
			(layer "F.Fab")
			(effects
				(font
					(size 1.27 1.27)
				)
			)
		)
		(duplicate_pad_numbers_are_jumpers no)
		(fp_rect
			(start -0.500126 1.598422)
			(end 0.500126 -0.201422)
			(stroke
				(width 0)
				(type default)
			)
			(fill no)
			(layer "F.CrtYd")
		)
		(fp_line
			(start -0.500126 1.598422)
			(end -0.500126 -0.201422)
			(stroke
				(width 0.1)
				(type default)
			)
			(layer "F.Fab")
		)
		(fp_line
			(start 0.500126 1.598422)
			(end -0.500126 1.598422)
			(stroke
				(width 0.1)
				(type default)
			)
			(layer "F.Fab")
		)
		(fp_line
			(start -0.500126 -0.201422)
			(end 0.500126 -0.201422)
			(stroke
				(width 0.1)
				(type default)
			)
			(layer "F.Fab")
		)
		(fp_line
			(start 0.500126 -0.201422)
			(end 0.500126 1.598422)
			(stroke
				(width 0.1)
				(type default)
			)
			(layer "F.Fab")
		)
		(pad "1" smd rect
			(at 0 0 180)
			(size 0.889 0.9906)
			(layers "F.Cu" "F.Mask" "F.Paste")
			(net "PVDDQ_ABC")
		)
		(pad "2" smd rect
			(at 0 1.397 180)
			(size 0.889 0.9906)
			(layers "F.Cu" "F.Mask" "F.Paste")
			(net "GND")
		)
		(zone
			(layer "F.Cu")
			(hatch none 0.5)
			(connect_pads
				(clearance 0)
			)
			(min_thickness 0.25)
			(keepout
				(tracks not_allowed)
				(vias allowed)
				(pads allowed)
				(copperpour not_allowed)
				(footprints allowed)
			)
			(placement
				(enabled no)
				(sheetname "")
			)
			(fill
				(thermal_gap 0.5)
				(thermal_bridge_width 0.5)
				(island_removal_mode 0)
			)
			(polygon
				(pts
					(xy 257.2131 -13.3985) (xy 257.2131 -12.4079) (xy 257.7211 -12.4079) (xy 257.7211 -13.3985)
				)
			)
		)
		(zone
			(layer "F.Cu")
			(hatch none 0.5)
			(connect_pads
				(clearance 0)
			)
			(min_thickness 0.25)
			(keepout
				(tracks allowed)
				(vias not_allowed)
				(pads allowed)
				(copperpour not_allowed)
				(footprints allowed)
			)
			(placement
				(enabled no)
				(sheetname "")
			)
			(fill
				(thermal_gap 0.5)
				(thermal_bridge_width 0.5)
				(island_removal_mode 0)
			)
			(polygon
				(pts
					(xy 257.2131 -13.3985) (xy 257.2131 -12.4079) (xy 257.7211 -12.4079) (xy 257.7211 -13.3985)
				)
			)
		)
	)
)
